(kicad_pcb
	(version 20260206)
	(generator "pcbnew")
	(generator_version "10.0")
	(general
		(thickness 1.6)
		(legacy_teardrops no)
	)
	(paper "A4")
	(title_block
		(title "Bryce Canyon_IOM_IOC_16318-2_OCP.brd")
		(comment 1 "Bryce Canyon / footprints 28-35 of 1605")
	)
	(layers
		(0 "F.Cu" signal "TOP")
		(4 "In1.Cu" signal "L2GND")
		(6 "In2.Cu" signal "L3")
		(8 "In3.Cu" signal "L4VCC")
		(10 "In4.Cu" signal "L5VCC")
		(12 "In5.Cu" signal "L6")
		(14 "In6.Cu" signal "L7GND")
		(2 "B.Cu" signal "BOTTOM")
		(9 "F.Adhes" user "F.Adhesive")
		(11 "B.Adhes" user "B.Adhesive")
		(13 "F.Paste" user "Package Geometry/Pastemask Top")
		(15 "B.Paste" user "Package Geometry/Pastemask Bottom")
		(5 "F.SilkS" user "Ref Des/Silkscreen Top")
		(7 "B.SilkS" user "Ref Des/Silkscreen Bottom")
		(1 "F.Mask" user "Board Geometry/Soldermask Top")
		(3 "B.Mask" user "Board Geometry/Soldermask Bottom")
		(17 "Dwgs.User" user "User.Drawings")
		(19 "Cmts.User" user "User.Comments")
		(21 "Eco1.User" user "User.Eco1")
		(23 "Eco2.User" user "User.Eco2")
		(25 "Edge.Cuts" user "Board Geometry/Outline")
		(27 "Margin" user)
		(31 "F.CrtYd" user "Package Geometry/Place Bound Top")
		(29 "B.CrtYd" user "Package Geometry/Place Bound Bottom")
		(35 "F.Fab" user "Ref Des/Assembly Top")
		(33 "B.Fab" user "Ref Des/Assembly Bottom")
	)
	(footprint ""
		(layer "F.Cu")
		(at 48.05299 -158.1912)
		(property "Reference" "R170"
			(at 0 0 0)
			(layer "F.SilkS")
			(hide yes)
			(effects
				(font
					(size 1.27 1.27)
				)
			)
		)
		(property "Value" "0R2J-2-GP"
			(at 0.064008 -3.993896 0)
			(unlocked yes)
			(layer "F.Fab")
			(hide yes)
			(effects
				(font
					(size 1.016 1.016)
					(thickness 0.1524)
				)
			)
		)
		(property "Device Type" "R402H16"
			(at 0.064008 -5.517896 0)
			(unlocked yes)
			(layer "F.Fab")
			(hide yes)
			(effects
				(font
					(size 1.016 1.016)
					(thickness 0.1524)
				)
			)
		)
		(duplicate_pad_numbers_are_jumpers no)
		(fp_line
			(start -0.508 -0.9398)
			(end -0.508 0.9398)
			(stroke
				(width 0.1524)
				(type default)
			)
			(layer "F.SilkS")
		)
		(fp_line
			(start 0.508 -0.9398)
			(end -0.508 -0.9398)
			(stroke
				(width 0.1524)
				(type default)
			)
			(layer "F.SilkS")
		)
		(fp_rect
			(start -0.508 0.9398)
			(end 0.508 -0.9398)
			(stroke
				(width 0)
				(type default)
			)
			(fill no)
			(layer "F.CrtYd")
		)
		(fp_rect
			(start -0.508 0.9398)
			(end 0.508 -0.9398)
			(stroke
				(width 0)
				(type default)
			)
			(fill no)
			(layer "F.Fab")
		)
		(pad "1" smd custom
			(at 0 -0.4445)
			(size 0.1397 0.1397)
			(layers "F.Cu" "F.Mask" "F.Paste")
			(net "I2C_DPB_MISC_SDA_OUT")
			(options
				(clearance outline)
				(anchor circle)
			)
			(primitives
				(gr_poly
					(pts
						(arc
							(start -0.1778 -0.2794)
							(mid -0.249642 -0.249642)
							(end -0.2794 -0.1778)
						)
						(arc
							(start -0.2794 0.1778)
							(mid -0.249642 0.249642)
							(end -0.1778 0.2794)
						)
						(arc
							(start 0.1778 0.2794)
							(mid 0.249642 0.249642)
							(end 0.2794 0.1778)
						)
						(arc
							(start 0.2794 -0.1778)
							(mid 0.249642 -0.249642)
							(end 0.1778 -0.2794)
						)
					)
					(width 0)
					(fill yes)
				)
			)
		)
		(pad "2" smd custom
			(at 0 0.4445)
			(size 0.1397 0.1397)
			(layers "F.Cu" "F.Mask" "F.Paste")
			(net "BMC_SMB6_DAT")
			(options
				(clearance outline)
				(anchor circle)
			)
			(primitives
				(gr_poly
					(pts
						(arc
							(start -0.1778 -0.2794)
							(mid -0.249642 -0.249642)
							(end -0.2794 -0.1778)
						)
						(arc
							(start -0.2794 0.1778)
							(mid -0.249642 0.249642)
							(end -0.1778 0.2794)
						)
						(arc
							(start 0.1778 0.2794)
							(mid 0.249642 0.249642)
							(end 0.2794 0.1778)
						)
						(arc
							(start 0.2794 -0.1778)
							(mid 0.249642 -0.249642)
							(end 0.1778 -0.2794)
						)
					)
					(width 0)
					(fill yes)
				)
			)
		)
	)
	(footprint ""
		(layer "F.Cu")
		(at 163.9062 -134.112)
		(property "Reference" "C203"
			(at 0 0 0)
			(layer "F.SilkS")
			(hide yes)
			(effects
				(font
					(size 1.27 1.27)
				)
			)
		)
		(property "Value" "SCD1U16V2KX-3GP"
			(at 1.1811 -2.7051 0)
			(unlocked yes)
			(layer "F.Fab")
			(hide yes)
			(effects
				(font
					(size 1.016 1.016)
					(thickness 0.1524)
				)
			)
		)
		(property "Device Type" "C402H22"
			(at 1.1811 -4.2291 0)
			(unlocked yes)
			(layer "F.Fab")
			(hide yes)
			(effects
				(font
					(size 1.016 1.016)
					(thickness 0.1524)
				)
			)
		)
		(duplicate_pad_numbers_are_jumpers no)
		(fp_rect
			(start -0.4318 0.9525)
			(end 0.4318 -0.9525)
			(stroke
				(width 0)
				(type default)
			)
			(fill no)
			(layer "F.CrtYd")
		)
		(fp_rect
			(start -0.4318 0.9525)
			(end 0.4318 -0.9525)
			(stroke
				(width 0)
				(type default)
			)
			(fill no)
			(layer "F.Fab")
		)
		(pad "1" smd custom
			(at 0 -0.4445)
			(size 0.1524 0.1524)
			(layers "F.Cu" "F.Mask" "F.Paste")
			(net "P12V_STBY_VIN_PU4")
			(options
				(clearance outline)
				(anchor circle)
			)
			(primitives
				(gr_poly
					(pts
						(arc
							(start 0.3048 -0.2032)
							(mid 0.275042 -0.275042)
							(end 0.2032 -0.3048)
						)
						(arc
							(start -0.2032 -0.3048)
							(mid -0.275042 -0.275042)
							(end -0.3048 -0.2032)
						)
						(arc
							(start -0.3048 0.2032)
							(mid -0.275042 0.275042)
							(end -0.2032 0.3048)
						)
						(arc
							(start 0.2032 0.3048)
							(mid 0.275042 0.275042)
							(end 0.3048 0.2032)
						)
					)
					(width 0)
					(fill yes)
				)
			)
		)
		(pad "2" smd custom
			(at 0 0.4445)
			(size 0.1524 0.1524)
			(layers "F.Cu" "F.Mask" "F.Paste")
			(net "GND")
			(options
				(clearance outline)
				(anchor circle)
			)
			(primitives
				(gr_poly
					(pts
						(arc
							(start 0.3048 -0.2032)
							(mid 0.275042 -0.275042)
							(end 0.2032 -0.3048)
						)
						(arc
							(start -0.2032 -0.3048)
							(mid -0.275042 -0.275042)
							(end -0.3048 -0.2032)
						)
						(arc
							(start -0.3048 0.2032)
							(mid -0.275042 0.275042)
							(end -0.2032 0.3048)
						)
						(arc
							(start 0.2032 0.3048)
							(mid 0.275042 0.275042)
							(end 0.3048 0.2032)
						)
					)
					(width 0)
					(fill yes)
				)
			)
		)
	)
	(footprint ""
		(layer "F.Cu")
		(at 174.4726 -65.913 90)
		(property "Reference" "R578"
			(at 0 0 90)
			(layer "F.SilkS")
			(hide yes)
			(effects
				(font
					(size 1.27 1.27)
				)
			)
		)
		(property "Value" "2K2R2F-GP"
			(at 0.064008 -3.993896 90)
			(unlocked yes)
			(layer "F.Fab")
			(hide yes)
			(effects
				(font
					(size 1.016 1.016)
					(thickness 0.1524)
				)
			)
		)
		(property "Device Type" "R402H16"
			(at 0.064008 -5.517896 90)
			(unlocked yes)
			(layer "F.Fab")
			(hide yes)
			(effects
				(font
					(size 1.016 1.016)
					(thickness 0.1524)
				)
			)
		)
		(duplicate_pad_numbers_are_jumpers no)
		(fp_line
			(start 0.508 -0.9398)
			(end -0.508 -0.9398)
			(stroke
				(width 0.1524)
				(type default)
			)
			(layer "F.SilkS")
		)
		(fp_line
			(start -0.508 -0.9398)
			(end -0.508 0.9398)
			(stroke
				(width 0.1524)
				(type default)
			)
			(layer "F.SilkS")
		)
		(fp_rect
			(start -0.508 0.9398)
			(end 0.508 -0.9398)
			(stroke
				(width 0)
				(type default)
			)
			(fill no)
			(layer "F.CrtYd")
		)
		(fp_rect
			(start -0.508 0.9398)
			(end 0.508 -0.9398)
			(stroke
				(width 0)
				(type default)
			)
			(fill no)
			(layer "F.Fab")
		)
		(pad "1" smd custom
			(at 0 -0.4445 90)
			(size 0.1397 0.1397)
			(layers "F.Cu" "F.Mask" "F.Paste")
			(net "P1V8")
			(options
				(clearance outline)
				(anchor circle)
			)
			(primitives
				(gr_poly
					(pts
						(arc
							(start -0.1778 -0.2794)
							(mid -0.249642 -0.249642)
							(end -0.2794 -0.1778)
						)
						(arc
							(start -0.2794 0.1778)
							(mid -0.249642 0.249642)
							(end -0.1778 0.2794)
						)
						(arc
							(start 0.1778 0.2794)
							(mid 0.249642 0.249642)
							(end 0.2794 0.1778)
						)
						(arc
							(start 0.2794 -0.1778)
							(mid 0.249642 -0.249642)
							(end 0.1778 -0.2794)
						)
					)
					(width 0)
					(fill yes)
				)
			)
		)
		(pad "2" smd custom
			(at 0 0.4445 90)
			(size 0.1397 0.1397)
			(layers "F.Cu" "F.Mask" "F.Paste")
			(net "SBL_SCL")
			(options
				(clearance outline)
				(anchor circle)
			)
			(primitives
				(gr_poly
					(pts
						(arc
							(start -0.1778 -0.2794)
							(mid -0.249642 -0.249642)
							(end -0.2794 -0.1778)
						)
						(arc
							(start -0.2794 0.1778)
							(mid -0.249642 0.249642)
							(end -0.1778 0.2794)
						)
						(arc
							(start 0.1778 0.2794)
							(mid 0.249642 0.249642)
							(end 0.2794 0.1778)
						)
						(arc
							(start 0.2794 -0.1778)
							(mid 0.249642 -0.249642)
							(end 0.1778 -0.2794)
						)
					)
					(width 0)
					(fill yes)
				)
			)
		)
	)
	(footprint ""
		(layer "F.Cu")
		(at 157.688788 -95.037656 180)
		(property "Reference" "R691"
			(at 0 0 180)
			(layer "F.SilkS")
			(hide yes)
			(effects
				(font
					(size 1.27 1.27)
				)
			)
		)
		(property "Value" "0R2J-2-GP"
			(at 0.064008 -3.993896 180)
			(unlocked yes)
			(layer "F.Fab")
			(hide yes)
			(effects
				(font
					(size 1.016 1.016)
					(thickness 0.1524)
				)
			)
		)
		(property "Device Type" "R402H16"
			(at 0.064008 -5.517896 180)
			(unlocked yes)
			(layer "F.Fab")
			(hide yes)
			(effects
				(font
					(size 1.016 1.016)
					(thickness 0.1524)
				)
			)
		)
		(duplicate_pad_numbers_are_jumpers no)
		(fp_line
			(start 0.508 -0.9398)
			(end -0.508 -0.9398)
			(stroke
				(width 0.1524)
				(type default)
			)
			(layer "F.SilkS")
		)
		(fp_line
			(start -0.508 -0.9398)
			(end -0.508 0.9398)
			(stroke
				(width 0.1524)
				(type default)
			)
			(layer "F.SilkS")
		)
		(fp_rect
			(start -0.508 0.9398)
			(end 0.508 -0.9398)
			(stroke
				(width 0)
				(type default)
			)
			(fill no)
			(layer "F.CrtYd")
		)
		(fp_rect
			(start -0.508 0.9398)
			(end 0.508 -0.9398)
			(stroke
				(width 0)
				(type default)
			)
			(fill no)
			(layer "F.Fab")
		)
		(pad "1" smd custom
			(at 0 -0.4445 180)
			(size 0.1397 0.1397)
			(layers "F.Cu" "F.Mask" "F.Paste")
			(net "IOC_UART_0_TX_R")
			(options
				(clearance outline)
				(anchor circle)
			)
			(primitives
				(gr_poly
					(pts
						(arc
							(start -0.1778 -0.2794)
							(mid -0.249642 -0.249642)
							(end -0.2794 -0.1778)
						)
						(arc
							(start -0.2794 0.1778)
							(mid -0.249642 0.249642)
							(end -0.1778 0.2794)
						)
						(arc
							(start 0.1778 0.2794)
							(mid 0.249642 0.249642)
							(end 0.2794 0.1778)
						)
						(arc
							(start 0.2794 -0.1778)
							(mid 0.249642 -0.249642)
							(end 0.1778 -0.2794)
						)
					)
					(width 0)
					(fill yes)
				)
			)
		)
		(pad "2" smd custom
			(at 0 0.4445 180)
			(size 0.1397 0.1397)
			(layers "F.Cu" "F.Mask" "F.Paste")
			(net "IOC_UART_0_TX")
			(options
				(clearance outline)
				(anchor circle)
			)
			(primitives
				(gr_poly
					(pts
						(arc
							(start -0.1778 -0.2794)
							(mid -0.249642 -0.249642)
							(end -0.2794 -0.1778)
						)
						(arc
							(start -0.2794 0.1778)
							(mid -0.249642 0.249642)
							(end -0.1778 0.2794)
						)
						(arc
							(start 0.1778 0.2794)
							(mid 0.249642 0.249642)
							(end 0.2794 0.1778)
						)
						(arc
							(start 0.2794 -0.1778)
							(mid 0.249642 -0.249642)
							(end 0.1778 -0.2794)
						)
					)
					(width 0)
					(fill yes)
				)
			)
		)
	)
	(footprint ""
		(layer "F.Cu")
		(at 83.312 -170.5864)
		(property "Reference" "R726"
			(at 0 0 0)
			(layer "F.SilkS")
			(hide yes)
			(effects
				(font
					(size 1.27 1.27)
				)
			)
		)
		(property "Value" "4K7R2F-GP"
			(at 0.064008 -3.993896 0)
			(unlocked yes)
			(layer "F.Fab")
			(hide yes)
			(effects
				(font
					(size 1.016 1.016)
					(thickness 0.1524)
				)
			)
		)
		(property "Device Type" "R402H16"
			(at 0.064008 -5.517896 0)
			(unlocked yes)
			(layer "F.Fab")
			(hide yes)
			(effects
				(font
					(size 1.016 1.016)
					(thickness 0.1524)
				)
			)
		)
		(duplicate_pad_numbers_are_jumpers no)
		(fp_line
			(start -0.508 -0.9398)
			(end -0.508 0.9398)
			(stroke
				(width 0.1524)
				(type default)
			)
			(layer "F.SilkS")
		)
		(fp_line
			(start 0.508 -0.9398)
			(end -0.508 -0.9398)
			(stroke
				(width 0.1524)
				(type default)
			)
			(layer "F.SilkS")
		)
		(fp_rect
			(start -0.508 0.9398)
			(end 0.508 -0.9398)
			(stroke
				(width 0)
				(type default)
			)
			(fill no)
			(layer "F.CrtYd")
		)
		(fp_rect
			(start -0.508 0.9398)
			(end 0.508 -0.9398)
			(stroke
				(width 0)
				(type default)
			)
			(fill no)
			(layer "F.Fab")
		)
		(pad "1" smd custom
			(at 0 -0.4445)
			(size 0.1397 0.1397)
			(layers "F.Cu" "F.Mask" "F.Paste")
			(net "P3V3_STBY")
			(options
				(clearance outline)
				(anchor circle)
			)
			(primitives
				(gr_poly
					(pts
						(arc
							(start -0.1778 -0.2794)
							(mid -0.249642 -0.249642)
							(end -0.2794 -0.1778)
						)
						(arc
							(start -0.2794 0.1778)
							(mid -0.249642 0.249642)
							(end -0.1778 0.2794)
						)
						(arc
							(start 0.1778 0.2794)
							(mid 0.249642 0.249642)
							(end 0.2794 0.1778)
						)
						(arc
							(start 0.2794 -0.1778)
							(mid 0.249642 -0.249642)
							(end 0.1778 -0.2794)
						)
					)
					(width 0)
					(fill yes)
				)
			)
		)
		(pad "2" smd custom
			(at 0 0.4445)
			(size 0.1397 0.1397)
			(layers "F.Cu" "F.Mask" "F.Paste")
			(net "IOM_STBY_PGOOD")
			(options
				(clearance outline)
				(anchor circle)
			)
			(primitives
				(gr_poly
					(pts
						(arc
							(start -0.1778 -0.2794)
							(mid -0.249642 -0.249642)
							(end -0.2794 -0.1778)
						)
						(arc
							(start -0.2794 0.1778)
							(mid -0.249642 0.249642)
							(end -0.1778 0.2794)
						)
						(arc
							(start 0.1778 0.2794)
							(mid 0.249642 0.249642)
							(end 0.2794 0.1778)
						)
						(arc
							(start 0.2794 -0.1778)
							(mid 0.249642 -0.249642)
							(end 0.1778 -0.2794)
						)
					)
					(width 0)
					(fill yes)
				)
			)
		)
	)
	(footprint ""
		(layer "F.Cu")
		(at 39.3954 -164.6936 90)
		(property "Reference" "R302"
			(at 0 0 90)
			(layer "F.SilkS")
			(hide yes)
			(effects
				(font
					(size 1.27 1.27)
				)
			)
		)
		(property "Value" "0R2J-2-GP"
			(at 0.064008 -3.993896 90)
			(unlocked yes)
			(layer "F.Fab")
			(hide yes)
			(effects
				(font
					(size 1.016 1.016)
					(thickness 0.1524)
				)
			)
		)
		(property "Device Type" "R402H16"
			(at 0.064008 -5.517896 90)
			(unlocked yes)
			(layer "F.Fab")
			(hide yes)
			(effects
				(font
					(size 1.016 1.016)
					(thickness 0.1524)
				)
			)
		)
		(duplicate_pad_numbers_are_jumpers no)
		(fp_line
			(start 0.508 -0.9398)
			(end -0.508 -0.9398)
			(stroke
				(width 0.1524)
				(type default)
			)
			(layer "F.SilkS")
		)
		(fp_line
			(start -0.508 -0.9398)
			(end -0.508 0.9398)
			(stroke
				(width 0.1524)
				(type default)
			)
			(layer "F.SilkS")
		)
		(fp_rect
			(start -0.508 0.9398)
			(end 0.508 -0.9398)
			(stroke
				(width 0)
				(type default)
			)
			(fill no)
			(layer "F.CrtYd")
		)
		(fp_rect
			(start -0.508 0.9398)
			(end 0.508 -0.9398)
			(stroke
				(width 0)
				(type default)
			)
			(fill no)
			(layer "F.Fab")
		)
		(pad "1" smd custom
			(at 0 -0.4445 90)
			(size 0.1397 0.1397)
			(layers "F.Cu" "F.Mask" "F.Paste")
			(net "UART_EXP_BMC_TX")
			(options
				(clearance outline)
				(anchor circle)
			)
			(primitives
				(gr_poly
					(pts
						(arc
							(start -0.1778 -0.2794)
							(mid -0.249642 -0.249642)
							(end -0.2794 -0.1778)
						)
						(arc
							(start -0.2794 0.1778)
							(mid -0.249642 0.249642)
							(end -0.1778 0.2794)
						)
						(arc
							(start 0.1778 0.2794)
							(mid 0.249642 0.249642)
							(end 0.2794 0.1778)
						)
						(arc
							(start 0.2794 -0.1778)
							(mid 0.249642 -0.249642)
							(end 0.1778 -0.2794)
						)
					)
					(width 0)
					(fill yes)
				)
			)
		)
		(pad "2" smd custom
			(at 0 0.4445 90)
			(size 0.1397 0.1397)
			(layers "F.Cu" "F.Mask" "F.Paste")
			(net "UART_EXP_BMC_TX_R")
			(options
				(clearance outline)
				(anchor circle)
			)
			(primitives
				(gr_poly
					(pts
						(arc
							(start -0.1778 -0.2794)
							(mid -0.249642 -0.249642)
							(end -0.2794 -0.1778)
						)
						(arc
							(start -0.2794 0.1778)
							(mid -0.249642 0.249642)
							(end -0.1778 0.2794)
						)
						(arc
							(start 0.1778 0.2794)
							(mid 0.249642 0.249642)
							(end 0.2794 0.1778)
						)
						(arc
							(start 0.2794 -0.1778)
							(mid 0.249642 -0.249642)
							(end 0.1778 -0.2794)
						)
					)
					(width 0)
					(fill yes)
				)
			)
		)
	)
	(footprint ""
		(layer "F.Cu")
		(at 187.600844 -86.54542)
		(property "Reference" "TP149"
			(at 0 0 0)
			(layer "F.SilkS")
			(hide yes)
			(effects
				(font
					(size 1.27 1.27)
				)
			)
		)
		(property "Value" "TPAD28-2-GP"
			(at -0.0127 -1.6637 0)
			(unlocked yes)
			(layer "F.Fab")
			(hide yes)
			(effects
				(font
					(size 1.016 1.016)
					(thickness 0.1524)
				)
			)
		)
		(property "Device Type" "TPAD28"
			(at -0.0127 -3.1877 0)
			(unlocked yes)
			(layer "F.Fab")
			(hide yes)
			(effects
				(font
					(size 1.016 1.016)
					(thickness 0.1524)
				)
			)
		)
		(duplicate_pad_numbers_are_jumpers no)
		(fp_poly
			(pts
				(arc
					(start 0.3556 0)
					(mid -0.3556 0)
					(end 0.3556 0)
				)
			)
			(stroke
				(width 0)
				(type default)
			)
			(fill no)
			(layer "F.CrtYd")
		)
		(fp_poly
			(pts
				(arc
					(start 0.6096 0)
					(mid -0.6096 0)
					(end 0.6096 0)
				)
			)
			(stroke
				(width 0)
				(type default)
			)
			(fill no)
			(layer "F.Fab")
		)
		(pad "1" smd circle
			(at 0 0)
			(size 0.7112 0.7112)
			(layers "F.Cu" "F.Mask" "F.Paste")
			(net "SYS_DBMODE1")
		)
	)
	(footprint ""
		(layer "F.Cu")
		(at 184.1754 -116.0526 90)
		(property "Reference" "C274"
			(at 0 0 90)
			(layer "F.SilkS")
			(hide yes)
			(effects
				(font
					(size 1.27 1.27)
				)
			)
		)
		(property "Value" "SC10U16V5KX-7-GP-U"
			(at -0.0762 -6.1214 90)
			(unlocked yes)
			(layer "F.Fab")
			(hide yes)
			(effects
				(font
					(size 1.016 1.016)
					(thickness 0.1524)
				)
			)
		)
		(property "Device Type" "C805H58"
			(at -0.0762 -8.1534 90)
			(unlocked yes)
			(layer "F.Fab")
			(hide yes)
			(effects
				(font
					(size 1.016 1.016)
					(thickness 0.1524)
				)
			)
		)
		(duplicate_pad_numbers_are_jumpers no)
		(fp_line
			(start 0.635 0)
			(end -0.635 0)
			(stroke
				(width 0.508)
				(type default)
			)
			(layer "F.SilkS")
		)
		(fp_rect
			(start -0.9652 1.778)
			(end 0.9652 -1.778)
			(stroke
				(width 0)
				(type default)
			)
			(fill no)
			(layer "F.CrtYd")
		)
		(fp_poly
			(pts
				(xy -0.9652 -1.778) (xy 0.9652 -1.778) (xy 0.9652 1.778) (xy -0.9652 1.778)
			)
			(stroke
				(width 0)
				(type default)
			)
			(fill no)
			(layer "F.Fab")
		)
		(pad "1" smd rect
			(at 0 -0.9652 90)
			(size 1.397 1.143)
			(layers "F.Cu" "F.Mask" "F.Paste")
			(net "VT235_VDDH")
		)
		(pad "2" smd rect
			(at 0 0.9652 90)
			(size 1.397 1.143)
			(layers "F.Cu" "F.Mask" "F.Paste")
			(net "GND")
		)
	)
)
